# S9S_MB_2U (Grand Teton) — schematic netlist excerpt (pin names and nets, part order shuffled) for the footprints in the layout excerpt that follows; sources: Cadence DE-HDL packaged netlist, KiCad conversion of 03242023_DA0F0TMBIJ0_F0T_Motherboard_J_brd_V01_OCP.brd

R3979  Q_RES  100K 1% CHIP  pkg 0402LF  page 192 : A = P3V3_AUX ; B = TP_P3V3_E1S_PWRGD_0
C1775  Q_CAP  0.1UF 25V 10% X7R  pkg 0402  page 246 : A = P3V3_AUX ; B = GND

(kicad_pcb
	(version 20260206)
	(generator "pcbnew")
	(generator_version "10.0")
	(general
		(thickness 1.6)
		(legacy_teardrops no)
	)
	(paper "A4")
	(title_block
		(title "03242023_DA0F0TMBIJ0_F0T_Motherboard_J_brd_V01_OCP.brd")
		(comment 1 "Grand Teton / footprints 718-719 of 6105")
	)
	(layers
		(0 "F.Cu" signal "TOP")
		(4 "In1.Cu" signal "GND")
		(6 "In2.Cu" signal "IN1")
		(8 "In3.Cu" signal "GND1")
		(10 "In4.Cu" signal "IN2")
		(12 "In5.Cu" signal "GND2")
		(14 "In6.Cu" signal "IN3")
		(16 "In7.Cu" signal "GND3")
		(18 "In8.Cu" signal "VCC")
		(20 "In9.Cu" signal "VCC1")
		(22 "In10.Cu" signal "GND4")
		(24 "In11.Cu" signal "IN4")
		(26 "In12.Cu" signal "GND5")
		(28 "In13.Cu" signal "IN5")
		(30 "In14.Cu" signal "GND6")
		(32 "In15.Cu" signal "IN6")
		(34 "In16.Cu" signal "GND7")
		(2 "B.Cu" signal "BOTTOM")
		(9 "F.Adhes" user "F.Adhesive")
		(11 "B.Adhes" user "B.Adhesive")
		(13 "F.Paste" user "Package Geometry/Pastemask Top")
		(15 "B.Paste" user "Package Geometry/Pastemask Bottom")
		(5 "F.SilkS" user "Ref Des/Silkscreen Top")
		(7 "B.SilkS" user "Ref Des/Silkscreen Bottom")
		(1 "F.Mask" user "Board Geometry/Soldermask Top")
		(3 "B.Mask" user "Board Geometry/Soldermask Bottom")
		(17 "Dwgs.User" user "User.Drawings")
		(19 "Cmts.User" user "User.Comments")
		(21 "Eco1.User" user "User.Eco1")
		(23 "Eco2.User" user "User.Eco2")
		(25 "Edge.Cuts" user "Board Geometry/Outline")
		(27 "Margin" user)
		(31 "F.CrtYd" user "Package Geometry/Place Bound Top")
		(29 "B.CrtYd" user "Package Geometry/Place Bound Bottom")
		(35 "F.Fab" user "Ref Des/Assembly Top")
		(33 "B.Fab" user "Ref Des/Assembly Bottom")
	)
	(footprint ""
		(layer "F.Cu")
		(at 193.60261 -431.424334 180)
		(property "Reference" "C1775"
			(at 0 0 180)
			(layer "F.SilkS")
			(hide yes)
			(effects
				(font
					(size 1.27 1.27)
				)
			)
		)
		(property "Value" ""
			(at 0 0 180)
			(layer "F.Fab")
			(effects
				(font
					(size 1.27 1.27)
				)
			)
		)
		(duplicate_pad_numbers_are_jumpers no)
		(fp_line
			(start 0.7874 0.4064)
			(end -0.7874 0.4064)
			(stroke
				(width 0.1524)
				(type default)
			)
			(layer "F.SilkS")
		)
		(fp_line
			(start 0.7874 -0.4064)
			(end 0.7874 0.4064)
			(stroke
				(width 0.1524)
				(type default)
			)
			(layer "F.SilkS")
		)
		(fp_line
			(start -0.7874 0.4064)
			(end -0.7874 -0.4064)
			(stroke
				(width 0.1524)
				(type default)
			)
			(layer "F.SilkS")
		)
		(fp_line
			(start -0.7874 -0.4064)
			(end 0.7874 -0.4064)
			(stroke
				(width 0.1524)
				(type default)
			)
			(layer "F.SilkS")
		)
		(fp_line
			(start 0.67945 0.3048)
			(end 0.120396 0.3048)
			(stroke
				(width 0.1)
				(type default)
			)
			(layer "F.Fab")
		)
		(fp_line
			(start 0.67945 -0.3048)
			(end 0.67945 0.3048)
			(stroke
				(width 0.1)
				(type default)
			)
			(layer "F.Fab")
		)
		(fp_line
			(start 0.12065 -0.2794)
			(end 0.12065 -0.3048)
			(stroke
				(width 0.1)
				(type default)
			)
			(layer "F.Fab")
		)
		(fp_line
			(start 0.12065 -0.3048)
			(end 0.67945 -0.3048)
			(stroke
				(width 0.1)
				(type default)
			)
			(layer "F.Fab")
		)
		(fp_line
			(start 0.120396 0.3048)
			(end 0.120396 0.2794)
			(stroke
				(width 0.1)
				(type default)
			)
			(layer "F.Fab")
		)
		(fp_line
			(start 0.120396 0.2794)
			(end -0.12065 0.2794)
			(stroke
				(width 0.1)
				(type default)
			)
			(layer "F.Fab")
		)
		(fp_line
			(start -0.12065 0.3048)
			(end -0.67945 0.3048)
			(stroke
				(width 0.1)
				(type default)
			)
			(layer "F.Fab")
		)
		(fp_line
			(start -0.12065 0.2794)
			(end -0.12065 0.3048)
			(stroke
				(width 0.1)
				(type default)
			)
			(layer "F.Fab")
		)
		(fp_line
			(start -0.12065 -0.2794)
			(end 0.12065 -0.2794)
			(stroke
				(width 0.1)
				(type default)
			)
			(layer "F.Fab")
		)
		(fp_line
			(start -0.12065 -0.305054)
			(end -0.12065 -0.2794)
			(stroke
				(width 0.1)
				(type default)
			)
			(layer "F.Fab")
		)
		(fp_line
			(start -0.67945 0.3048)
			(end -0.67945 -0.305054)
			(stroke
				(width 0.1)
				(type default)
			)
			(layer "F.Fab")
		)
		(fp_line
			(start -0.67945 -0.305054)
			(end -0.12065 -0.305054)
			(stroke
				(width 0.1)
				(type default)
			)
			(layer "F.Fab")
		)
		(pad "1" smd circle
			(at -0.40005 0 180)
			(size 0 0)
			(layers "F.Cu" "F.Mask" "F.Paste")
			(net "P3V3_AUX")
		)
		(pad "2" smd circle
			(at 0.40005 0 180)
			(size 0 0)
			(layers "F.Cu" "F.Mask" "F.Paste")
			(net "GND")
		)
	)
	(footprint ""
		(layer "F.Cu")
		(at 225.171762 -69.318378 -90)
		(property "Reference" "R3979"
			(at 0 0 270)
			(layer "F.SilkS")
			(hide yes)
			(effects
				(font
					(size 1.27 1.27)
				)
			)
		)
		(property "Value" ""
			(at 0 0 270)
			(layer "F.Fab")
			(effects
				(font
					(size 1.27 1.27)
				)
			)
		)
		(duplicate_pad_numbers_are_jumpers no)
		(fp_line
			(start -0.7874 0.4064)
			(end -0.7874 -0.4064)
			(stroke
				(width 0.1524)
				(type default)
			)
			(layer "F.SilkS")
		)
		(fp_line
			(start 0.7874 0.4064)
			(end -0.7874 0.4064)
			(stroke
				(width 0.1524)
				(type default)
			)
			(layer "F.SilkS")
		)
		(fp_line
			(start -0.7874 -0.4064)
			(end 0.7874 -0.4064)
			(stroke
				(width 0.1524)
				(type default)
			)
			(layer "F.SilkS")
		)
		(fp_line
			(start 0.7874 -0.4064)
			(end 0.7874 0.4064)
			(stroke
				(width 0.1524)
				(type default)
			)
			(layer "F.SilkS")
		)
		(fp_line
			(start -0.67945 0.3048)
			(end -0.67945 -0.305054)
			(stroke
				(width 0.1)
				(type default)
			)
			(layer "F.Fab")
		)
		(fp_line
			(start -0.12065 0.3048)
			(end -0.67945 0.3048)
			(stroke
				(width 0.1)
				(type default)
			)
			(layer "F.Fab")
		)
		(fp_line
			(start 0.120396 0.3048)
			(end 0.120396 0.2794)
			(stroke
				(width 0.1)
				(type default)
			)
			(layer "F.Fab")
		)
		(fp_line
			(start 0.67945 0.3048)
			(end 0.120396 0.3048)
			(stroke
				(width 0.1)
				(type default)
			)
			(layer "F.Fab")
		)
		(fp_line
			(start -0.12065 0.2794)
			(end -0.12065 0.3048)
			(stroke
				(width 0.1)
				(type default)
			)
			(layer "F.Fab")
		)
		(fp_line
			(start 0.120396 0.2794)
			(end -0.12065 0.2794)
			(stroke
				(width 0.1)
				(type default)
			)
			(layer "F.Fab")
		)
		(fp_line
			(start -0.12065 -0.2794)
			(end 0.12065 -0.2794)
			(stroke
				(width 0.1)
				(type default)
			)
			(layer "F.Fab")
		)
		(fp_line
			(start 0.12065 -0.2794)
			(end 0.12065 -0.3048)
			(stroke
				(width 0.1)
				(type default)
			)
			(layer "F.Fab")
		)
		(fp_line
			(start 0.12065 -0.3048)
			(end 0.67945 -0.3048)
			(stroke
				(width 0.1)
				(type default)
			)
			(layer "F.Fab")
		)
		(fp_line
			(start 0.67945 -0.3048)
			(end 0.67945 0.3048)
			(stroke
				(width 0.1)
				(type default)
			)
			(layer "F.Fab")
		)
		(fp_line
			(start -0.67945 -0.305054)
			(end -0.12065 -0.305054)
			(stroke
				(width 0.1)
				(type default)
			)
			(layer "F.Fab")
		)
		(fp_line
			(start -0.12065 -0.305054)
			(end -0.12065 -0.2794)
			(stroke
				(width 0.1)
				(type default)
			)
			(layer "F.Fab")
		)
		(pad "1" smd circle
			(at -0.40005 0 270)
			(size 0 0)
			(layers "F.Cu" "F.Mask" "F.Paste")
			(net "P3V3_AUX")
		)
		(pad "2" smd circle
			(at 0.40005 0 270)
			(size 0 0)
			(layers "F.Cu" "F.Mask" "F.Paste")
			(net "TP_P3V3_E1S_PWRGD_0")
		)
	)
)
